# T6G (Grand Teton) — schematic netlist excerpt (pin names and nets, part order shuffled) for the footprints in the layout excerpt that follows; sources: Cadence DE-HDL packaged netlist, KiCad conversion of 04192023_DAF0TMB3IC0_F0TG_MB_C_brd_V02_OCP.brd

R1627  Q_RES  1K 1% CHIP  pkg 0402LF  page 172 : A = PVDD18_S5_P0 ; B = HDT_HDR_TDI
R578  Q_RES  4.75K 1% EMPTY  pkg 0402LF  page 183 : A = P3V3_AUX ; B = CLK_9ZXL045_P1_SADR0

(kicad_pcb
	(version 20260206)
	(generator "pcbnew")
	(generator_version "10.0")
	(general
		(thickness 1.6)
		(legacy_teardrops no)
	)
	(paper "A4")
	(title_block
		(title "04192023_DAF0TMB3IC0_F0TG_MB_C_brd_V02_OCP.brd")
		(comment 1 "Grand Teton / footprints 2288-2289 of 8354")
	)
	(layers
		(0 "F.Cu" signal "TOP")
		(4 "In1.Cu" signal "GND")
		(6 "In2.Cu" signal "IN1")
		(8 "In3.Cu" signal "GND1")
		(10 "In4.Cu" signal "IN2")
		(12 "In5.Cu" signal "GND2")
		(14 "In6.Cu" signal "IN3")
		(16 "In7.Cu" signal "GND3")
		(18 "In8.Cu" signal "VCC")
		(20 "In9.Cu" signal "VCC1")
		(22 "In10.Cu" signal "GND4")
		(24 "In11.Cu" signal "IN4")
		(26 "In12.Cu" signal "GND5")
		(28 "In13.Cu" signal "IN5")
		(30 "In14.Cu" signal "GND6")
		(32 "In15.Cu" signal "IN6")
		(34 "In16.Cu" signal "GND7")
		(2 "B.Cu" signal "BOTTOM")
		(9 "F.Adhes" user "F.Adhesive")
		(11 "B.Adhes" user "B.Adhesive")
		(13 "F.Paste" user "Package Geometry/Pastemask Top")
		(15 "B.Paste" user "Package Geometry/Pastemask Bottom")
		(5 "F.SilkS" user "Ref Des/Silkscreen Top")
		(7 "B.SilkS" user "Ref Des/Silkscreen Bottom")
		(1 "F.Mask" user "Board Geometry/Soldermask Top")
		(3 "B.Mask" user "Board Geometry/Soldermask Bottom")
		(17 "Dwgs.User" user "User.Drawings")
		(19 "Cmts.User" user "User.Comments")
		(21 "Eco1.User" user "User.Eco1")
		(23 "Eco2.User" user "User.Eco2")
		(25 "Edge.Cuts" user "Board Geometry/Outline")
		(27 "Margin" user)
		(31 "F.CrtYd" user "Package Geometry/Place Bound Top")
		(29 "B.CrtYd" user "Package Geometry/Place Bound Bottom")
		(35 "F.Fab" user "Ref Des/Assembly Top")
		(33 "B.Fab" user "Ref Des/Assembly Bottom")
	)
	(footprint ""
		(layer "F.Cu")
		(at 386.211826 -57.2135 180)
		(property "Reference" "R1627"
			(at 0 0 180)
			(layer "F.SilkS")
			(hide yes)
			(effects
				(font
					(size 1.27 1.27)
				)
			)
		)
		(property "Value" ""
			(at 0 0 180)
			(layer "F.Fab")
			(effects
				(font
					(size 1.27 1.27)
				)
			)
		)
		(duplicate_pad_numbers_are_jumpers no)
		(fp_line
			(start 0.7874 0.4064)
			(end -0.7874 0.4064)
			(stroke
				(width 0.1524)
				(type default)
			)
			(layer "F.SilkS")
		)
		(fp_line
			(start 0.7874 -0.4064)
			(end 0.7874 0.4064)
			(stroke
				(width 0.1524)
				(type default)
			)
			(layer "F.SilkS")
		)
		(fp_line
			(start -0.7874 0.4064)
			(end -0.7874 -0.4064)
			(stroke
				(width 0.1524)
				(type default)
			)
			(layer "F.SilkS")
		)
		(fp_line
			(start -0.7874 -0.4064)
			(end 0.7874 -0.4064)
			(stroke
				(width 0.1524)
				(type default)
			)
			(layer "F.SilkS")
		)
		(fp_line
			(start 0.67945 0.3048)
			(end 0.120396 0.3048)
			(stroke
				(width 0.1)
				(type default)
			)
			(layer "F.Fab")
		)
		(fp_line
			(start 0.67945 -0.3048)
			(end 0.67945 0.3048)
			(stroke
				(width 0.1)
				(type default)
			)
			(layer "F.Fab")
		)
		(fp_line
			(start 0.12065 -0.2794)
			(end 0.12065 -0.3048)
			(stroke
				(width 0.1)
				(type default)
			)
			(layer "F.Fab")
		)
		(fp_line
			(start 0.12065 -0.3048)
			(end 0.67945 -0.3048)
			(stroke
				(width 0.1)
				(type default)
			)
			(layer "F.Fab")
		)
		(fp_line
			(start 0.120396 0.3048)
			(end 0.120396 0.2794)
			(stroke
				(width 0.1)
				(type default)
			)
			(layer "F.Fab")
		)
		(fp_line
			(start 0.120396 0.2794)
			(end -0.12065 0.2794)
			(stroke
				(width 0.1)
				(type default)
			)
			(layer "F.Fab")
		)
		(fp_line
			(start -0.12065 0.3048)
			(end -0.67945 0.3048)
			(stroke
				(width 0.1)
				(type default)
			)
			(layer "F.Fab")
		)
		(fp_line
			(start -0.12065 0.2794)
			(end -0.12065 0.3048)
			(stroke
				(width 0.1)
				(type default)
			)
			(layer "F.Fab")
		)
		(fp_line
			(start -0.12065 -0.2794)
			(end 0.12065 -0.2794)
			(stroke
				(width 0.1)
				(type default)
			)
			(layer "F.Fab")
		)
		(fp_line
			(start -0.12065 -0.305054)
			(end -0.12065 -0.2794)
			(stroke
				(width 0.1)
				(type default)
			)
			(layer "F.Fab")
		)
		(fp_line
			(start -0.67945 0.3048)
			(end -0.67945 -0.305054)
			(stroke
				(width 0.1)
				(type default)
			)
			(layer "F.Fab")
		)
		(fp_line
			(start -0.67945 -0.305054)
			(end -0.12065 -0.305054)
			(stroke
				(width 0.1)
				(type default)
			)
			(layer "F.Fab")
		)
		(pad "1" smd circle
			(at -0.40005 0 180)
			(size 0 0)
			(layers "F.Cu" "F.Mask" "F.Paste")
			(net "PVDD18_S5_P0")
		)
		(pad "2" smd circle
			(at 0.40005 0 180)
			(size 0 0)
			(layers "F.Cu" "F.Mask" "F.Paste")
			(net "HDT_HDR_TDI")
		)
	)
	(footprint ""
		(layer "F.Cu")
		(at 104.267 -415.798)
		(property "Reference" "R578"
			(at 0 0 0)
			(layer "F.SilkS")
			(hide yes)
			(effects
				(font
					(size 1.27 1.27)
				)
			)
		)
		(property "Value" ""
			(at 0 0 0)
			(layer "F.Fab")
			(effects
				(font
					(size 1.27 1.27)
				)
			)
		)
		(duplicate_pad_numbers_are_jumpers no)
		(fp_line
			(start -0.7874 -0.4064)
			(end 0.7874 -0.4064)
			(stroke
				(width 0.1524)
				(type default)
			)
			(layer "F.SilkS")
		)
		(fp_line
			(start -0.7874 0.4064)
			(end -0.7874 -0.4064)
			(stroke
				(width 0.1524)
				(type default)
			)
			(layer "F.SilkS")
		)
		(fp_line
			(start 0.7874 -0.4064)
			(end 0.7874 0.4064)
			(stroke
				(width 0.1524)
				(type default)
			)
			(layer "F.SilkS")
		)
		(fp_line
			(start 0.7874 0.4064)
			(end -0.7874 0.4064)
			(stroke
				(width 0.1524)
				(type default)
			)
			(layer "F.SilkS")
		)
		(fp_line
			(start -0.67945 -0.305054)
			(end -0.12065 -0.305054)
			(stroke
				(width 0.1)
				(type default)
			)
			(layer "F.Fab")
		)
		(fp_line
			(start -0.67945 0.3048)
			(end -0.67945 -0.305054)
			(stroke
				(width 0.1)
				(type default)
			)
			(layer "F.Fab")
		)
		(fp_line
			(start -0.12065 -0.305054)
			(end -0.12065 -0.2794)
			(stroke
				(width 0.1)
				(type default)
			)
			(layer "F.Fab")
		)
		(fp_line
			(start -0.12065 -0.2794)
			(end 0.12065 -0.2794)
			(stroke
				(width 0.1)
				(type default)
			)
			(layer "F.Fab")
		)
		(fp_line
			(start -0.12065 0.2794)
			(end -0.12065 0.3048)
			(stroke
				(width 0.1)
				(type default)
			)
			(layer "F.Fab")
		)
		(fp_line
			(start -0.12065 0.3048)
			(end -0.67945 0.3048)
			(stroke
				(width 0.1)
				(type default)
			)
			(layer "F.Fab")
		)
		(fp_line
			(start 0.120396 0.2794)
			(end -0.12065 0.2794)
			(stroke
				(width 0.1)
				(type default)
			)
			(layer "F.Fab")
		)
		(fp_line
			(start 0.120396 0.3048)
			(end 0.120396 0.2794)
			(stroke
				(width 0.1)
				(type default)
			)
			(layer "F.Fab")
		)
		(fp_line
			(start 0.12065 -0.3048)
			(end 0.67945 -0.3048)
			(stroke
				(width 0.1)
				(type default)
			)
			(layer "F.Fab")
		)
		(fp_line
			(start 0.12065 -0.2794)
			(end 0.12065 -0.3048)
			(stroke
				(width 0.1)
				(type default)
			)
			(layer "F.Fab")
		)
		(fp_line
			(start 0.67945 -0.3048)
			(end 0.67945 0.3048)
			(stroke
				(width 0.1)
				(type default)
			)
			(layer "F.Fab")
		)
		(fp_line
			(start 0.67945 0.3048)
			(end 0.120396 0.3048)
			(stroke
				(width 0.1)
				(type default)
			)
			(layer "F.Fab")
		)
		(pad "1" smd circle
			(at -0.40005 0)
			(size 0 0)
			(layers "F.Cu" "F.Mask" "F.Paste")
			(net "P3V3_AUX")
		)
		(pad "2" smd circle
			(at 0.40005 0)
			(size 0 0)
			(layers "F.Cu" "F.Mask" "F.Paste")
			(net "CLK_9ZXL045_P1_SADR0")
		)
	)
)
